# S9S_MB_2U (Grand Teton) — schematic netlist excerpt (pin names and nets, part order shuffled) for the footprints in the layout excerpt that follows; sources: Cadence DE-HDL packaged netlist, KiCad conversion of 03242023_DA0F0TMBIJ0_F0T_Motherboard_J_brd_V01_OCP.brd

R2561  Q_RES  0 5% CHIP  pkg 0402LF  page 292 : A = SVID_ALERT0_CPU1_R_N ; B = SVID_ALERT_PVCCINFAON_CPU1_R
R3481  Q_RES  33.2 1% CHIP  pkg 0402LF  page 213 : A = GPU_HMC_PRSNT_ISO_N ; B = GPU_HMC_PRSNT_ISO_R_N

(kicad_pcb
	(version 20260206)
	(generator "pcbnew")
	(generator_version "10.0")
	(general
		(thickness 1.6)
		(legacy_teardrops no)
	)
	(paper "A4")
	(title_block
		(title "03242023_DA0F0TMBIJ0_F0T_Motherboard_J_brd_V01_OCP.brd")
		(comment 1 "Grand Teton / footprints 577-578 of 6105")
	)
	(layers
		(0 "F.Cu" signal "TOP")
		(4 "In1.Cu" signal "GND")
		(6 "In2.Cu" signal "IN1")
		(8 "In3.Cu" signal "GND1")
		(10 "In4.Cu" signal "IN2")
		(12 "In5.Cu" signal "GND2")
		(14 "In6.Cu" signal "IN3")
		(16 "In7.Cu" signal "GND3")
		(18 "In8.Cu" signal "VCC")
		(20 "In9.Cu" signal "VCC1")
		(22 "In10.Cu" signal "GND4")
		(24 "In11.Cu" signal "IN4")
		(26 "In12.Cu" signal "GND5")
		(28 "In13.Cu" signal "IN5")
		(30 "In14.Cu" signal "GND6")
		(32 "In15.Cu" signal "IN6")
		(34 "In16.Cu" signal "GND7")
		(2 "B.Cu" signal "BOTTOM")
		(9 "F.Adhes" user "F.Adhesive")
		(11 "B.Adhes" user "B.Adhesive")
		(13 "F.Paste" user "Package Geometry/Pastemask Top")
		(15 "B.Paste" user "Package Geometry/Pastemask Bottom")
		(5 "F.SilkS" user "Ref Des/Silkscreen Top")
		(7 "B.SilkS" user "Ref Des/Silkscreen Bottom")
		(1 "F.Mask" user "Board Geometry/Soldermask Top")
		(3 "B.Mask" user "Board Geometry/Soldermask Bottom")
		(17 "Dwgs.User" user "User.Drawings")
		(19 "Cmts.User" user "User.Comments")
		(21 "Eco1.User" user "User.Eco1")
		(23 "Eco2.User" user "User.Eco2")
		(25 "Edge.Cuts" user "Board Geometry/Outline")
		(27 "Margin" user)
		(31 "F.CrtYd" user "Package Geometry/Place Bound Top")
		(29 "B.CrtYd" user "Package Geometry/Place Bound Bottom")
		(35 "F.Fab" user "Ref Des/Assembly Top")
		(33 "B.Fab" user "Ref Des/Assembly Bottom")
	)
	(footprint ""
		(layer "F.Cu")
		(at 36.956238 -131.77774 180)
		(property "Reference" "R2561"
			(at 0 0 180)
			(layer "F.SilkS")
			(hide yes)
			(effects
				(font
					(size 1.27 1.27)
				)
			)
		)
		(property "Value" ""
			(at 0 0 180)
			(layer "F.Fab")
			(effects
				(font
					(size 1.27 1.27)
				)
			)
		)
		(duplicate_pad_numbers_are_jumpers no)
		(fp_line
			(start 0.7874 0.4064)
			(end -0.7874 0.4064)
			(stroke
				(width 0.1524)
				(type default)
			)
			(layer "F.SilkS")
		)
		(fp_line
			(start 0.7874 -0.4064)
			(end 0.7874 0.4064)
			(stroke
				(width 0.1524)
				(type default)
			)
			(layer "F.SilkS")
		)
		(fp_line
			(start -0.7874 0.4064)
			(end -0.7874 -0.4064)
			(stroke
				(width 0.1524)
				(type default)
			)
			(layer "F.SilkS")
		)
		(fp_line
			(start -0.7874 -0.4064)
			(end 0.7874 -0.4064)
			(stroke
				(width 0.1524)
				(type default)
			)
			(layer "F.SilkS")
		)
		(fp_line
			(start 0.67945 0.3048)
			(end 0.120396 0.3048)
			(stroke
				(width 0.1)
				(type default)
			)
			(layer "F.Fab")
		)
		(fp_line
			(start 0.67945 -0.3048)
			(end 0.67945 0.3048)
			(stroke
				(width 0.1)
				(type default)
			)
			(layer "F.Fab")
		)
		(fp_line
			(start 0.12065 -0.2794)
			(end 0.12065 -0.3048)
			(stroke
				(width 0.1)
				(type default)
			)
			(layer "F.Fab")
		)
		(fp_line
			(start 0.12065 -0.3048)
			(end 0.67945 -0.3048)
			(stroke
				(width 0.1)
				(type default)
			)
			(layer "F.Fab")
		)
		(fp_line
			(start 0.120396 0.3048)
			(end 0.120396 0.2794)
			(stroke
				(width 0.1)
				(type default)
			)
			(layer "F.Fab")
		)
		(fp_line
			(start 0.120396 0.2794)
			(end -0.12065 0.2794)
			(stroke
				(width 0.1)
				(type default)
			)
			(layer "F.Fab")
		)
		(fp_line
			(start -0.12065 0.3048)
			(end -0.67945 0.3048)
			(stroke
				(width 0.1)
				(type default)
			)
			(layer "F.Fab")
		)
		(fp_line
			(start -0.12065 0.2794)
			(end -0.12065 0.3048)
			(stroke
				(width 0.1)
				(type default)
			)
			(layer "F.Fab")
		)
		(fp_line
			(start -0.12065 -0.2794)
			(end 0.12065 -0.2794)
			(stroke
				(width 0.1)
				(type default)
			)
			(layer "F.Fab")
		)
		(fp_line
			(start -0.12065 -0.305054)
			(end -0.12065 -0.2794)
			(stroke
				(width 0.1)
				(type default)
			)
			(layer "F.Fab")
		)
		(fp_line
			(start -0.67945 0.3048)
			(end -0.67945 -0.305054)
			(stroke
				(width 0.1)
				(type default)
			)
			(layer "F.Fab")
		)
		(fp_line
			(start -0.67945 -0.305054)
			(end -0.12065 -0.305054)
			(stroke
				(width 0.1)
				(type default)
			)
			(layer "F.Fab")
		)
		(pad "1" smd circle
			(at -0.40005 0 180)
			(size 0 0)
			(layers "F.Cu" "F.Mask" "F.Paste")
			(net "SVID_ALERT0_CPU1_R_N")
		)
		(pad "2" smd circle
			(at 0.40005 0 180)
			(size 0 0)
			(layers "F.Cu" "F.Mask" "F.Paste")
			(net "SVID_ALERT_PVCCINFAON_CPU1_R")
		)
	)
	(footprint ""
		(layer "F.Cu")
		(at 157.02788 -112.486948)
		(property "Reference" "R3481"
			(at 0 0 0)
			(layer "F.SilkS")
			(hide yes)
			(effects
				(font
					(size 1.27 1.27)
				)
			)
		)
		(property "Value" ""
			(at 0 0 0)
			(layer "F.Fab")
			(effects
				(font
					(size 1.27 1.27)
				)
			)
		)
		(duplicate_pad_numbers_are_jumpers no)
		(fp_line
			(start -0.7874 -0.4064)
			(end 0.7874 -0.4064)
			(stroke
				(width 0.1524)
				(type default)
			)
			(layer "F.SilkS")
		)
		(fp_line
			(start -0.7874 0.4064)
			(end -0.7874 -0.4064)
			(stroke
				(width 0.1524)
				(type default)
			)
			(layer "F.SilkS")
		)
		(fp_line
			(start 0.7874 -0.4064)
			(end 0.7874 0.4064)
			(stroke
				(width 0.1524)
				(type default)
			)
			(layer "F.SilkS")
		)
		(fp_line
			(start 0.7874 0.4064)
			(end -0.7874 0.4064)
			(stroke
				(width 0.1524)
				(type default)
			)
			(layer "F.SilkS")
		)
		(fp_line
			(start -0.67945 -0.305054)
			(end -0.12065 -0.305054)
			(stroke
				(width 0.1)
				(type default)
			)
			(layer "F.Fab")
		)
		(fp_line
			(start -0.67945 0.3048)
			(end -0.67945 -0.305054)
			(stroke
				(width 0.1)
				(type default)
			)
			(layer "F.Fab")
		)
		(fp_line
			(start -0.12065 -0.305054)
			(end -0.12065 -0.2794)
			(stroke
				(width 0.1)
				(type default)
			)
			(layer "F.Fab")
		)
		(fp_line
			(start -0.12065 -0.2794)
			(end 0.12065 -0.2794)
			(stroke
				(width 0.1)
				(type default)
			)
			(layer "F.Fab")
		)
		(fp_line
			(start -0.12065 0.2794)
			(end -0.12065 0.3048)
			(stroke
				(width 0.1)
				(type default)
			)
			(layer "F.Fab")
		)
		(fp_line
			(start -0.12065 0.3048)
			(end -0.67945 0.3048)
			(stroke
				(width 0.1)
				(type default)
			)
			(layer "F.Fab")
		)
		(fp_line
			(start 0.120396 0.2794)
			(end -0.12065 0.2794)
			(stroke
				(width 0.1)
				(type default)
			)
			(layer "F.Fab")
		)
		(fp_line
			(start 0.120396 0.3048)
			(end 0.120396 0.2794)
			(stroke
				(width 0.1)
				(type default)
			)
			(layer "F.Fab")
		)
		(fp_line
			(start 0.12065 -0.3048)
			(end 0.67945 -0.3048)
			(stroke
				(width 0.1)
				(type default)
			)
			(layer "F.Fab")
		)
		(fp_line
			(start 0.12065 -0.2794)
			(end 0.12065 -0.3048)
			(stroke
				(width 0.1)
				(type default)
			)
			(layer "F.Fab")
		)
		(fp_line
			(start 0.67945 -0.3048)
			(end 0.67945 0.3048)
			(stroke
				(width 0.1)
				(type default)
			)
			(layer "F.Fab")
		)
		(fp_line
			(start 0.67945 0.3048)
			(end 0.120396 0.3048)
			(stroke
				(width 0.1)
				(type default)
			)
			(layer "F.Fab")
		)
		(pad "1" smd circle
			(at -0.40005 0)
			(size 0 0)
			(layers "F.Cu" "F.Mask" "F.Paste")
			(net "GPU_HMC_PRSNT_ISO_N")
		)
		(pad "2" smd circle
			(at 0.40005 0)
			(size 0 0)
			(layers "F.Cu" "F.Mask" "F.Paste")
			(net "GPU_HMC_PRSNT_ISO_R_N")
		)
	)
)
